# TIMECARD (Time Appliance Project (Time Card)) — schematic netlist excerpt (pin names and nets, part order shuffled) for the footprints in the layout excerpt that follows; sources: Cadence DE-HDL packaged netlist, KiCad conversion of R4006-B0001-02_R01.brd

U5  TPS54824RNVR_VQFN18  TPS54424RNVT  pkg QFN18_138_P0197_V1  page 32
  BOOT  = XP5R0V_BT
  VIN_1  = VIN_XP5R0V
  PGND_1  = SG
  PGND_2  = SG
  PGND_3  = SG
  SW_1  = XP5R0V_SW
  SW_2  = XP5R0V_SW
  PGND_4  = SG
  PGND_5  = SG
  PGND_6  = SG
  VIN_2  = VIN_XP5R0V
  AGND  = XP5R0V_AGND
  \rt/clk\  = XP5R0V_RT
  FB  = XP5R0V_FB_R_TO_AGND
  COMP  = XP5R0V_COMP
  \ss/trk\  = XP5R0V_SS
  EN  = R_XP5R0V_EN
  PGOOD  = XP5R0V_PG

(kicad_pcb
	(version 20260206)
	(generator "pcbnew")
	(generator_version "10.0")
	(general
		(thickness 1.6)
		(legacy_teardrops no)
	)
	(paper "A4")
	(title_block
		(title "timecard-production-celestica-r4006 — R4006-B0001-02_R01.brd")
		(comment 1 "Time Appliance Project (Time Card) / footprints 348-348 of 1113")
	)
	(layers
		(0 "F.Cu" signal "TOP")
		(4 "In1.Cu" signal "L02_GND1")
		(6 "In2.Cu" signal "L03_SIG1")
		(8 "In3.Cu" signal "L04_GND2")
		(10 "In4.Cu" signal "L05_VCC1")
		(12 "In5.Cu" signal "L06_VCC2")
		(14 "In6.Cu" signal "L07_GND3")
		(16 "In7.Cu" signal "L08_SIG2")
		(18 "In8.Cu" signal "L09_GND4")
		(2 "B.Cu" signal "BOTTOM")
		(9 "F.Adhes" user "F.Adhesive")
		(11 "B.Adhes" user "B.Adhesive")
		(13 "F.Paste" user "Package Geometry/Pastemask Top")
		(15 "B.Paste" user "Package Geometry/Pastemask Bottom")
		(5 "F.SilkS" user "Ref Des/Silkscreen Top")
		(7 "B.SilkS" user "Ref Des/Silkscreen Bottom")
		(1 "F.Mask" user "Board Geometry/Soldermask Top")
		(3 "B.Mask" user "Board Geometry/Soldermask Bottom")
		(17 "Dwgs.User" user "User.Drawings")
		(19 "Cmts.User" user "User.Comments")
		(21 "Eco1.User" user "User.Eco1")
		(23 "Eco2.User" user "User.Eco2")
		(25 "Edge.Cuts" user "Board Geometry/Outline")
		(27 "Margin" user)
		(31 "F.CrtYd" user "Package Geometry/Place Bound Top")
		(29 "B.CrtYd" user "Package Geometry/Place Bound Bottom")
		(35 "F.Fab" user "Ref Des/Assembly Top")
		(33 "B.Fab" user "Ref Des/Assembly Bottom")
	)
	(footprint ""
		(layer "F.Cu")
		(at 41.8084 -100.7364 90)
		(property "Reference" "U5"
			(at -6.66877 1.4986 0)
			(unlocked yes)
			(layer "F.SilkS")
			(effects
				(font
					(size 0.7874 0.5842)
					(thickness 0.1524)
				)
			)
		)
		(property "Value" ""
			(at 0 0 90)
			(layer "F.Fab")
			(effects
				(font
					(size 1.27 1.27)
				)
			)
		)
		(property "User Part Number" "PARTNUM*"
			(at 0.33782 5.715254 90)
			(unlocked yes)
			(layer "Cmts.User")
			(hide yes)
			(effects
				(font
					(size 0.7874 0.5842)
					(thickness 0.1524)
				)
			)
		)
		(property "Device Type" "TPS54824RNVR_VQFN18-G220-10657A"
			(at 0.33782 4.521454 90)
			(unlocked yes)
			(layer "F.Fab")
			(hide yes)
			(effects
				(font
					(size 0.7874 0.5842)
					(thickness 0.1524)
				)
			)
		)
		(duplicate_pad_numbers_are_jumpers no)
		(fp_line
			(start 2.208784 -2.208784)
			(end 2.208784 2.200148)
			(stroke
				(width 0.1)
				(type default)
			)
			(layer "F.SilkS")
		)
		(fp_line
			(start -2.208784 -2.208784)
			(end 2.208784 -2.208784)
			(stroke
				(width 0.1)
				(type default)
			)
			(layer "F.SilkS")
		)
		(fp_line
			(start 2.208784 2.200148)
			(end -2.208784 2.200148)
			(stroke
				(width 0.1)
				(type default)
			)
			(layer "F.SilkS")
		)
		(fp_line
			(start -2.208784 2.200148)
			(end -2.208784 -2.208784)
			(stroke
				(width 0.1)
				(type default)
			)
			(layer "F.SilkS")
		)
		(fp_poly
			(pts
				(arc
					(start -3.084068 -0.48514)
					(mid -3.084068 -1.50114)
					(end -3.084068 -0.48514)
				)
			)
			(stroke
				(width 0)
				(type default)
			)
			(fill yes)
			(layer "F.SilkS")
		)
		(fp_rect
			(start 2.462784 2.454148)
			(end -2.462784 -2.462784)
			(stroke
				(width 0)
				(type default)
			)
			(fill no)
			(layer "F.CrtYd")
		)
		(fp_line
			(start 1.800098 -1.800098)
			(end 1.800098 1.800098)
			(stroke
				(width 0.1)
				(type default)
			)
			(layer "F.Fab")
		)
		(fp_line
			(start -1.800098 -1.800098)
			(end 1.800098 -1.800098)
			(stroke
				(width 0.1)
				(type default)
			)
			(layer "F.Fab")
		)
		(fp_line
			(start 1.800098 1.800098)
			(end -1.800098 1.800098)
			(stroke
				(width 0.1)
				(type default)
			)
			(layer "F.Fab")
		)
		(fp_line
			(start -1.800098 1.800098)
			(end -1.800098 -1.800098)
			(stroke
				(width 0.1)
				(type default)
			)
			(layer "F.Fab")
		)
		(fp_circle
			(center -3.084068 -0.99314)
			(end -3.084068 -0.48514)
			(stroke
				(width 0.1)
				(type default)
			)
			(fill no)
			(layer "F.Fab")
		)
		(fp_text user "13"
			(at 1.6256 -2.78765 90)
			(unlocked yes)
			(layer "F.SilkS")
			(effects
				(font
					(size 0.635 0.4064)
					(thickness 0.1524)
				)
			)
		)
		(fp_text user "18"
			(at -2.3114 -2.66065 90)
			(unlocked yes)
			(layer "F.SilkS")
			(effects
				(font
					(size 0.635 0.4064)
					(thickness 0.1524)
				)
			)
		)
		(fp_text user "12"
			(at 2.73685 -1.0414 0)
			(unlocked yes)
			(layer "F.SilkS")
			(effects
				(font
					(size 0.635 0.4064)
					(thickness 0.1524)
				)
			)
		)
		(fp_text user "8"
			(at 2.60985 2.1336 0)
			(unlocked yes)
			(layer "F.SilkS")
			(effects
				(font
					(size 0.635 0.4064)
					(thickness 0.1524)
				)
			)
		)
		(fp_text user "5"
			(at -1.65735 2.6924 0)
			(unlocked yes)
			(layer "F.SilkS")
			(effects
				(font
					(size 0.635 0.4064)
					(thickness 0.1524)
				)
			)
		)
		(fp_text user "7"
			(at 1.64465 2.8956 0)
			(unlocked yes)
			(layer "F.SilkS")
			(effects
				(font
					(size 0.635 0.4064)
					(thickness 0.1524)
				)
			)
		)
		(fp_text user "6"
			(at -0.81915 3.1496 0)
			(unlocked yes)
			(layer "F.SilkS")
			(effects
				(font
					(size 0.635 0.4064)
					(thickness 0.1524)
				)
			)
		)
		(fp_text user "18"
			(at -1.44907 -2.8194 0)
			(unlocked yes)
			(layer "F.Fab")
			(effects
				(font
					(size 0.7874 0.5842)
					(thickness 0.1524)
				)
			)
		)
		(fp_text user "13"
			(at 1.59893 -2.6924 0)
			(unlocked yes)
			(layer "F.Fab")
			(effects
				(font
					(size 0.7874 0.5842)
					(thickness 0.1524)
				)
			)
		)
		(fp_text user "12"
			(at 2.61493 -1.6764 0)
			(unlocked yes)
			(layer "F.Fab")
			(effects
				(font
					(size 0.7874 0.5842)
					(thickness 0.1524)
				)
			)
		)
		(fp_text user "5"
			(at -2.33807 1.3716 0)
			(unlocked yes)
			(layer "F.Fab")
			(effects
				(font
					(size 0.7874 0.5842)
					(thickness 0.1524)
				)
			)
		)
		(fp_text user "8"
			(at 2.36093 1.6256 0)
			(unlocked yes)
			(layer "F.Fab")
			(effects
				(font
					(size 0.7874 0.5842)
					(thickness 0.1524)
				)
			)
		)
		(fp_text user "7"
			(at 1.34493 2.2606 0)
			(unlocked yes)
			(layer "F.Fab")
			(effects
				(font
					(size 0.7874 0.5842)
					(thickness 0.1524)
				)
			)
		)
		(fp_text user "6"
			(at -1.57607 2.3876 0)
			(unlocked yes)
			(layer "F.Fab")
			(effects
				(font
					(size 0.7874 0.5842)
					(thickness 0.1524)
				)
			)
		)
		(pad "1" smd rect
			(at -1.649984 -0.94996 90)
			(size 0.6096 0.3048)
			(layers "F.Cu" "F.Mask" "F.Paste")
			(net "XP5R0V_BT")
		)
		(pad "2" smd rect
			(at -1.374902 -0.350012 90)
			(size 1.143 0.4064)
			(layers "F.Cu" "F.Mask" "F.Paste")
			(net "VIN_XP5R0V")
		)
		(pad "3" smd rect
			(at -1.374902 0.299974 90)
			(size 1.143 0.3048)
			(layers "F.Cu" "F.Mask" "F.Paste")
			(net "SG")
		)
		(pad "4" smd rect
			(at -1.374902 0.849884 90)
			(size 1.143 0.3048)
			(layers "F.Cu" "F.Mask" "F.Paste")
			(net "SG")
		)
		(pad "5" smd rect
			(at -1.374902 1.400048 90)
			(size 1.143 0.3048)
			(layers "F.Cu" "F.Mask" "F.Paste")
			(net "SG")
		)
		(pad "6" smd rect
			(at -0.32512 0.599948 90)
			(size 0.2032 2.6924)
			(layers "F.Cu" "F.Mask" "F.Paste")
			(net "XP5R0V_SW")
		)
		(pad "7" smd rect
			(at 0.32512 0.599948 90)
			(size 0.2032 2.6924)
			(layers "F.Cu" "F.Mask" "F.Paste")
			(net "XP5R0V_SW")
		)
		(pad "8" smd rect
			(at 1.374902 1.400048 90)
			(size 1.143 0.3048)
			(layers "F.Cu" "F.Mask" "F.Paste")
			(net "SG")
		)
		(pad "9" smd rect
			(at 1.374902 0.849884 90)
			(size 1.143 0.3048)
			(layers "F.Cu" "F.Mask" "F.Paste")
			(net "SG")
		)
		(pad "10" smd rect
			(at 1.374902 0.299974 90)
			(size 1.143 0.3048)
			(layers "F.Cu" "F.Mask" "F.Paste")
			(net "SG")
		)
		(pad "11" smd rect
			(at 1.374902 -0.350012 90)
			(size 1.143 0.4064)
			(layers "F.Cu" "F.Mask" "F.Paste")
			(net "VIN_XP5R0V")
		)
		(pad "12" smd rect
			(at 1.649984 -0.94996 90)
			(size 0.6096 0.3048)
			(layers "F.Cu" "F.Mask" "F.Paste")
			(net "XP5R0V_AGND")
		)
		(pad "13" smd rect
			(at 1.374902 -1.649984 90)
			(size 0.508 0.6096)
			(layers "F.Cu" "F.Mask" "F.Paste")
			(net "XP5R0V_RT")
		)
		(pad "14" smd rect
			(at 0.750062 -1.649984 90)
			(size 0.254 0.6096)
			(layers "F.Cu" "F.Mask" "F.Paste")
			(net "XP5R0V_FB_R_TO_AGND")
		)
		(pad "15" smd rect
			(at 0.249936 -1.649984 90)
			(size 0.254 0.6096)
			(layers "F.Cu" "F.Mask" "F.Paste")
			(net "XP5R0V_COMP")
		)
		(pad "16" smd rect
			(at -0.249936 -1.649984 90)
			(size 0.254 0.6096)
			(layers "F.Cu" "F.Mask" "F.Paste")
			(net "XP5R0V_SS")
		)
		(pad "17" smd rect
			(at -0.750062 -1.649984 90)
			(size 0.254 0.6096)
			(layers "F.Cu" "F.Mask" "F.Paste")
			(net "R_XP5R0V_EN")
		)
		(pad "18" smd rect
			(at -1.374902 -1.649984 90)
			(size 0.508 0.6096)
			(layers "F.Cu" "F.Mask" "F.Paste")
			(net "XP5R0V_PG")
		)
	)
)
